#ISCELL
  mstr_misc dns *
  *
#ISCELL
  pure_quanta quanta_title_block_c *
  *
#ISCELL
  pure_quanta_power vcc_core *
  page409_i10
#ISCELL
  pure_quanta_power universal_gnd *
  page409_i11
#ISCELL
  pure_quanta_power universal_gnd *
  page409_i12
#CELL
  pure_quanta q_res *
  page409_i13
#ISCELL
  pure_quanta_power universal_gnd *
  page409_i14
#CELL
  pure_quanta q_res *
  page409_i15
#ISCELL
  pure_quanta_power universal_gnd *
  page409_i16
#CELL
  pure_quanta pt5161lrs *
  page409_i17
#CELL
  pure_quanta q_res *
  page409_i18
#CELL
  pure_quanta q_res *
  page409_i19
#ISCELL
  pure_quanta_power p1v0 *
  page409_i2
#ISCELL
  pure_quanta_power universal_gnd *
  page409_i3
#CELL
  pure_quanta pt5161lrs *
  page409_i5
#ISCELL
  pure_quanta_power p1v0 *
  page409_i6
#ISCELL
  pure_quanta_power p1v0 *
  page409_i7
#ISCELL
  pure_quanta_power p1v0 *
  page409_i8
#ISCELL
  pure_quanta_power vcc_core *
  page409_i9
